(kicad_pcb
	(version 20241229)
	(generator "pcbnew")
	(generator_version "9.0")
	(general
		(thickness 1.6642)
		(legacy_teardrops no)
	)
	(paper "A3")
	(title_block
		(title "PolarFire SoM")
		(date "2025-07-22")
		(rev "1.1.4")
		(company "Antmicro Ltd")
		(comment 1 "www.antmicro.com")
		(comment 9 "footprints 456-460 of 470")
	)
	(layers
		(0 "F.Cu" mixed)
		(4 "In1.Cu" power)
		(6 "In2.Cu" signal)
		(8 "In3.Cu" power)
		(10 "In4.Cu" signal)
		(12 "In5.Cu" power)
		(14 "In6.Cu" power)
		(16 "In7.Cu" signal)
		(18 "In8.Cu" power)
		(20 "In9.Cu" signal)
		(22 "In10.Cu" power)
		(24 "In11.Cu" signal)
		(26 "In12.Cu" signal)
		(2 "B.Cu" mixed)
		(9 "F.Adhes" user "F.Adhesive")
		(11 "B.Adhes" user "B.Adhesive")
		(13 "F.Paste" user)
		(15 "B.Paste" user)
		(5 "F.SilkS" user "F.Silkscreen")
		(7 "B.SilkS" user "B.Silkscreen")
		(1 "F.Mask" user)
		(3 "B.Mask" user)
		(17 "Dwgs.User" user "User.Drawings")
		(19 "Cmts.User" user "User.Comments")
		(21 "Eco1.User" user "User.Eco1")
		(23 "Eco2.User" user "User.Eco2")
		(25 "Edge.Cuts" user)
		(27 "Margin" user)
		(31 "F.CrtYd" user "F.Courtyard")
		(29 "B.CrtYd" user "B.Courtyard")
		(35 "F.Fab" user)
		(33 "B.Fab" user)
	)
	(footprint "antmicro-footprints:C_0402_1005Metric"
		(layer "B.Cu")
		(at 208.1 149.38 180)
		(descr "Capacitor SMD 0402")
		(tags "capacitor SMD 0402")
		(property "Reference" "C249"
			(at 4.9 18.375 0)
			(layer "B.SilkS")
			(effects
				(font
					(size 0.7 0.7)
					(thickness 0.15)
				)
				(justify left bottom mirror)
			)
		)
		(property "Value" "C_10u_10V_0402"
			(at -1.022927 -2.155213 0)
			(layer "B.Fab")
			(hide yes)
			(effects
				(font
					(size 0.7 0.7)
					(thickness 0.15)
				)
				(justify left bottom mirror)
			)
		)
		(property "Datasheet" "https://www.murata.com/products/productdetail?partno=GRM155R61A106ME11%23"
			(at 0 0 180)
			(layer "F.Fab")
			(hide yes)
			(effects
				(font
					(size 1.27 1.27)
					(thickness 0.15)
				)
			)
		)
		(property "Description" "Multilayer Ceramic Capacitors MLCC - SMD/SMT 10 uF 10 VDC 20% 0402 X5R"
			(at 0 0 180)
			(layer "F.Fab")
			(hide yes)
			(effects
				(font
					(size 1.27 1.27)
					(thickness 0.15)
				)
			)
		)
		(property "Author" "Antmicro"
			(at 416.2 298.76 0)
			(layer "B.Fab")
			(hide yes)
			(effects
				(font
					(size 1 1)
					(thickness 0.15)
				)
				(justify mirror)
			)
		)
		(property "Dielectric" "X5R"
			(at 416.2 298.76 0)
			(layer "B.Fab")
			(hide yes)
			(effects
				(font
					(size 1 1)
					(thickness 0.15)
				)
				(justify mirror)
			)
		)
		(property "License" "Apache-2.0"
			(at 416.2 298.76 0)
			(layer "B.Fab")
			(hide yes)
			(effects
				(font
					(size 1 1)
					(thickness 0.15)
				)
				(justify mirror)
			)
		)
		(property "MPN" "GRM155R61A106ME11D"
			(at 416.2 298.76 0)
			(layer "B.Fab")
			(hide yes)
			(effects
				(font
					(size 1 1)
					(thickness 0.15)
				)
				(justify mirror)
			)
		)
		(property "Manufacturer" "Murata"
			(at 416.2 298.76 0)
			(layer "B.Fab")
			(hide yes)
			(effects
				(font
					(size 1 1)
					(thickness 0.15)
				)
				(justify mirror)
			)
		)
		(property "Public" ""
			(at 416.2 298.76 0)
			(layer "B.Fab")
			(hide yes)
			(effects
				(font
					(size 1 1)
					(thickness 0.15)
				)
				(justify mirror)
			)
		)
		(property "Val" "10u"
			(at 416.2 298.76 0)
			(layer "B.Fab")
			(hide yes)
			(effects
				(font
					(size 1 1)
					(thickness 0.15)
				)
				(justify mirror)
			)
		)
		(property "Voltage" "10V"
			(at 416.2 298.76 0)
			(layer "B.Fab")
			(hide yes)
			(effects
				(font
					(size 1 1)
					(thickness 0.15)
				)
				(justify mirror)
			)
		)
		(sheetname "/MIPI CrossLink/")
		(sheetfile "crosslink.kicad_sch")
		(attr smd)
		(fp_rect
			(start -0.925 0.47)
			(end 0.925 -0.47)
			(stroke
				(width 0.05)
				(type default)
			)
			(fill no)
			(layer "B.CrtYd")
		)
		(fp_line
			(start 0.504 0.25)
			(end 0.504 -0.248)
			(stroke
				(width 0.15)
				(type solid)
			)
			(layer "B.Fab")
		)
		(fp_line
			(start 0.504 -0.248)
			(end -0.494 -0.248)
			(stroke
				(width 0.15)
				(type solid)
			)
			(layer "B.Fab")
		)
		(fp_line
			(start -0.494 0.25)
			(end 0.504 0.25)
			(stroke
				(width 0.15)
				(type solid)
			)
			(layer "B.Fab")
		)
		(fp_line
			(start -0.494 -0.248)
			(end -0.494 0.25)
			(stroke
				(width 0.15)
				(type solid)
			)
			(layer "B.Fab")
		)
		(fp_text user "License: Apache-2.0"
			(at -0.939 -5.799 0)
			(layer "B.Fab")
			(effects
				(font
					(size 0.7 0.7)
					(thickness 0.15)
				)
				(justify left bottom mirror)
			)
		)
		(fp_text user "${REFERENCE}"
			(at -0.939 -4.599 0)
			(layer "B.Fab")
			(effects
				(font
					(size 0.7 0.7)
					(thickness 0.15)
				)
				(justify left bottom mirror)
			)
		)
		(fp_text user "Author: Antmicro"
			(at -0.939 -3.399 0)
			(layer "B.Fab")
			(effects
				(font
					(size 0.7 0.7)
					(thickness 0.15)
				)
				(justify left bottom mirror)
			)
		)
		(pad "1" smd roundrect
			(at -0.48 0 180)
			(size 0.59 0.64)
			(layers "B.Cu" "B.Mask" "B.Paste")
			(roundrect_rratio 0.25)
			(net 417 "GND")
			(pintype "passive")
		)
		(pad "2" smd roundrect
			(at 0.48 0 180)
			(size 0.59 0.64)
			(layers "B.Cu" "B.Mask" "B.Paste")
			(roundrect_rratio 0.25)
			(net 211 "/MIPI CrossLink/CL_VCCPLL_DPHY1")
			(pintype "passive")
		)
	)
	(footprint "antmicro-footprints:TP_SMD_0.75mm"
		(layer "B.Cu")
		(at 190.75 144.95 180)
		(property "Reference" "TP38"
			(at 0 0.6 0)
			(layer "B.SilkS")
			(hide yes)
			(effects
				(font
					(size 0.7 0.7)
					(thickness 0.15)
				)
				(justify left bottom mirror)
			)
		)
		(property "Value" "TP_0.75mm_SMD"
			(at 0 -1.2 0)
			(layer "B.Fab")
			(hide yes)
			(effects
				(font
					(size 0.7 0.7)
					(thickness 0.15)
				)
				(justify left bottom mirror)
			)
		)
		(property "Description" "SMT test point"
			(at 0 0 0)
			(layer "B.Fab")
			(hide yes)
			(effects
				(font
					(size 1.27 1.27)
					(thickness 0.15)
				)
				(justify mirror)
			)
		)
		(property "MPN" ""
			(at 0 0 0)
			(unlocked yes)
			(layer "B.Fab")
			(hide yes)
			(effects
				(font
					(size 1 1)
					(thickness 0.15)
				)
				(justify mirror)
			)
		)
		(property "Manufacturer" ""
			(at 0 0 0)
			(unlocked yes)
			(layer "B.Fab")
			(hide yes)
			(effects
				(font
					(size 1 1)
					(thickness 0.15)
				)
				(justify mirror)
			)
		)
		(property "Author" "Antmicro"
			(at 0 0 0)
			(unlocked yes)
			(layer "B.Fab")
			(hide yes)
			(effects
				(font
					(size 1 1)
					(thickness 0.15)
				)
				(justify mirror)
			)
		)
		(property "License" "Apache-2.0"
			(at 0 0 0)
			(unlocked yes)
			(layer "B.Fab")
			(hide yes)
			(effects
				(font
					(size 1 1)
					(thickness 0.15)
				)
				(justify mirror)
			)
		)
		(property "Public" "False"
			(at 0 0 0)
			(unlocked yes)
			(layer "B.Fab")
			(hide yes)
			(effects
				(font
					(size 1 1)
					(thickness 0.15)
				)
				(justify mirror)
			)
		)
		(sheetname "/Supply/")
		(sheetfile "supply.kicad_sch")
		(attr exclude_from_pos_files exclude_from_bom)
		(fp_circle
			(center 0 0)
			(end 0.475 0)
			(stroke
				(width 0.05)
				(type default)
			)
			(fill no)
			(layer "B.CrtYd")
		)
		(fp_text user "Author: Antmicro"
			(at -0.4 -3.901 0)
			(layer "B.Fab")
			(effects
				(font
					(size 0.7 0.7)
					(thickness 0.15)
				)
				(justify left bottom mirror)
			)
		)
		(fp_text user "${REFERENCE}"
			(at -0.4 -2.7 0)
			(layer "B.Fab")
			(effects
				(font
					(size 0.7 0.7)
					(thickness 0.15)
				)
				(justify left bottom mirror)
			)
		)
		(fp_text user "License: Apache-2.0"
			(at -0.4 -5.101 0)
			(layer "B.Fab")
			(effects
				(font
					(size 0.7 0.7)
					(thickness 0.15)
				)
				(justify left bottom mirror)
			)
		)
		(pad "1" smd circle
			(at 0 0 180)
			(size 0.75 0.75)
			(layers "B.Cu" "B.Mask")
			(net 417 "GND")
			(pinfunction "1")
			(pintype "passive")
		)
	)
	(footprint "antmicro-footprints:R_0402_1005Metric"
		(layer "B.Cu")
		(at 216.015 142.6 -90)
		(descr "Resistor SMD 0402")
		(tags "resistor SMD 0402")
		(property "Reference" "R66"
			(at -1.15 -1.435 90)
			(layer "B.SilkS")
			(effects
				(font
					(size 0.7 0.7)
					(thickness 0.15)
				)
				(justify left bottom mirror)
			)
		)
		(property "Value" "R_270k_0402"
			(at -1.011843 -1.772047 90)
			(layer "B.Fab")
			(hide yes)
			(effects
				(font
					(size 0.7 0.7)
					(thickness 0.15)
				)
				(justify left bottom mirror)
			)
		)
		(property "Datasheet" "https://www.bourns.com/docs/product-datasheets/cr.pdf"
			(at 0 0 270)
			(layer "F.Fab")
			(hide yes)
			(effects
				(font
					(size 1.27 1.27)
					(thickness 0.15)
				)
			)
		)
		(property "Description" "SMD Chip Resistor"
			(at 0 0 270)
			(layer "F.Fab")
			(hide yes)
			(effects
				(font
					(size 1.27 1.27)
					(thickness 0.15)
				)
			)
		)
		(property "Author" "Antmicro"
			(at 73.415 358.615 0)
			(layer "B.Fab")
			(hide yes)
			(effects
				(font
					(size 1 1)
					(thickness 0.15)
				)
				(justify mirror)
			)
		)
		(property "License" "Apache-2.0"
			(at 73.415 358.615 0)
			(layer "B.Fab")
			(hide yes)
			(effects
				(font
					(size 1 1)
					(thickness 0.15)
				)
				(justify mirror)
			)
		)
		(property "MPN" "CR0402-FX-2703GLF"
			(at 73.415 358.615 0)
			(layer "B.Fab")
			(hide yes)
			(effects
				(font
					(size 1 1)
					(thickness 0.15)
				)
				(justify mirror)
			)
		)
		(property "Manufacturer" "Bourns"
			(at 73.415 358.615 0)
			(layer "B.Fab")
			(hide yes)
			(effects
				(font
					(size 1 1)
					(thickness 0.15)
				)
				(justify mirror)
			)
		)
		(property "Public" ""
			(at 73.415 358.615 0)
			(layer "B.Fab")
			(hide yes)
			(effects
				(font
					(size 1 1)
					(thickness 0.15)
				)
				(justify mirror)
			)
		)
		(property "Tolerance" "1%"
			(at 73.415 358.615 0)
			(layer "B.Fab")
			(hide yes)
			(effects
				(font
					(size 1 1)
					(thickness 0.15)
				)
				(justify mirror)
			)
		)
		(property "Val" "270k"
			(at 73.415 358.615 0)
			(layer "B.Fab")
			(hide yes)
			(effects
				(font
					(size 1 1)
					(thickness 0.15)
				)
				(justify mirror)
			)
		)
		(sheetname "/USB/")
		(sheetfile "usb.kicad_sch")
		(attr smd)
		(fp_rect
			(start -0.925 0.47)
			(end 0.925 -0.47)
			(stroke
				(width 0.05)
				(type default)
			)
			(fill no)
			(layer "B.CrtYd")
		)
		(fp_rect
			(start -0.5 0.25)
			(end 0.5 -0.25)
			(stroke
				(width 0.15)
				(type solid)
			)
			(fill no)
			(layer "B.Fab")
		)
		(fp_text user "License: Apache-2.0"
			(at -0.95 -5.169 90)
			(layer "B.Fab")
			(effects
				(font
					(size 0.7 0.7)
					(thickness 0.15)
				)
				(justify left bottom mirror)
			)
		)
		(fp_text user "Author: Antmicro"
			(at -0.95 -4.169 90)
			(layer "B.Fab")
			(effects
				(font
					(size 0.7 0.7)
					(thickness 0.15)
				)
				(justify left bottom mirror)
			)
		)
		(fp_text user "${REFERENCE}"
			(at -0.95 -3.168 90)
			(layer "B.Fab")
			(effects
				(font
					(size 0.7 0.7)
					(thickness 0.15)
				)
				(justify left bottom mirror)
			)
		)
		(pad "1" smd roundrect
			(at -0.48 0 270)
			(size 0.59 0.64)
			(layers "B.Cu" "B.Mask" "B.Paste")
			(roundrect_rratio 0.25)
			(net 636 "/FPGA GPIO/ULPI.CLK")
			(pintype "passive")
		)
		(pad "2" smd roundrect
			(at 0.48 0 270)
			(size 0.59 0.64)
			(layers "B.Cu" "B.Mask" "B.Paste")
			(roundrect_rratio 0.25)
			(net 152 "/USB/VDDIO")
			(pintype "passive")
		)
	)
	(footprint "antmicro-footprints:C_0402_1005Metric"
		(layer "B.Cu")
		(at 197.99 134.73 90)
		(descr "Capacitor SMD 0402")
		(tags "capacitor SMD 0402")
		(property "Reference" "C55"
			(at 6.98 -9.565 270)
			(layer "B.SilkS")
			(effects
				(font
					(size 0.7 0.7)
					(thickness 0.15)
				)
				(justify left bottom mirror)
			)
		)
		(property "Value" "C_10n_0402"
			(at -1.022927 -2.155213 270)
			(layer "B.Fab")
			(hide yes)
			(effects
				(font
					(size 0.7 0.7)
					(thickness 0.15)
				)
				(justify left bottom mirror)
			)
		)
		(property "Datasheet" "https://www.murata.com/products/productdetail?partno=GRM155R71H103KA88%23"
			(at 0 0 90)
			(layer "F.Fab")
			(hide yes)
			(effects
				(font
					(size 1.27 1.27)
					(thickness 0.15)
				)
			)
		)
		(property "Description" "SMD Multilayer Ceramic Capacitor, 10000 pF, 50 V, 0402 [1005 Metric], ± 10%, X7R, GRM Series"
			(at 0 0 90)
			(layer "F.Fab")
			(hide yes)
			(effects
				(font
					(size 1.27 1.27)
					(thickness 0.15)
				)
			)
		)
		(property "Author" "Antmicro"
			(at 332.72 -63.26 0)
			(layer "B.Fab")
			(hide yes)
			(effects
				(font
					(size 1 1)
					(thickness 0.15)
				)
				(justify mirror)
			)
		)
		(property "Dielectric" "X7R"
			(at 332.72 -63.26 0)
			(layer "B.Fab")
			(hide yes)
			(effects
				(font
					(size 1 1)
					(thickness 0.15)
				)
				(justify mirror)
			)
		)
		(property "License" "Apache-2.0"
			(at 332.72 -63.26 0)
			(layer "B.Fab")
			(hide yes)
			(effects
				(font
					(size 1 1)
					(thickness 0.15)
				)
				(justify mirror)
			)
		)
		(property "MPN" "GRM155R71H103KA88D"
			(at 332.72 -63.26 0)
			(layer "B.Fab")
			(hide yes)
			(effects
				(font
					(size 1 1)
					(thickness 0.15)
				)
				(justify mirror)
			)
		)
		(property "Manufacturer" "Murata"
			(at 332.72 -63.26 0)
			(layer "B.Fab")
			(hide yes)
			(effects
				(font
					(size 1 1)
					(thickness 0.15)
				)
				(justify mirror)
			)
		)
		(property "Public" ""
			(at 332.72 -63.26 0)
			(layer "B.Fab")
			(hide yes)
			(effects
				(font
					(size 1 1)
					(thickness 0.15)
				)
				(justify mirror)
			)
		)
		(property "Val" "10n"
			(at 332.72 -63.26 0)
			(layer "B.Fab")
			(hide yes)
			(effects
				(font
					(size 1 1)
					(thickness 0.15)
				)
				(justify mirror)
			)
		)
		(property "Voltage" "50V"
			(at 332.72 -63.26 0)
			(layer "B.Fab")
			(hide yes)
			(effects
				(font
					(size 1 1)
					(thickness 0.15)
				)
				(justify mirror)
			)
		)
		(sheetname "/FPGA Supply/")
		(sheetfile "fpga-supply.kicad_sch")
		(attr smd)
		(fp_rect
			(start -0.925 0.47)
			(end 0.925 -0.47)
			(stroke
				(width 0.05)
				(type default)
			)
			(fill no)
			(layer "B.CrtYd")
		)
		(fp_line
			(start 0.504 -0.248)
			(end -0.494 -0.248)
			(stroke
				(width 0.15)
				(type solid)
			)
			(layer "B.Fab")
		)
		(fp_line
			(start -0.494 -0.248)
			(end -0.494 0.25)
			(stroke
				(width 0.15)
				(type solid)
			)
			(layer "B.Fab")
		)
		(fp_line
			(start 0.504 0.25)
			(end 0.504 -0.248)
			(stroke
				(width 0.15)
				(type solid)
			)
			(layer "B.Fab")
		)
		(fp_line
			(start -0.494 0.25)
			(end 0.504 0.25)
			(stroke
				(width 0.15)
				(type solid)
			)
			(layer "B.Fab")
		)
		(fp_text user "License: Apache-2.0"
			(at -0.939 -5.799 270)
			(layer "B.Fab")
			(effects
				(font
					(size 0.7 0.7)
					(thickness 0.15)
				)
				(justify left bottom mirror)
			)
		)
		(fp_text user "Author: Antmicro"
			(at -0.939 -3.399 270)
			(layer "B.Fab")
			(effects
				(font
					(size 0.7 0.7)
					(thickness 0.15)
				)
				(justify left bottom mirror)
			)
		)
		(fp_text user "${REFERENCE}"
			(at -0.939 -4.599 270)
			(layer "B.Fab")
			(effects
				(font
					(size 0.7 0.7)
					(thickness 0.15)
				)
				(justify left bottom mirror)
			)
		)
		(pad "1" smd roundrect
			(at -0.48 0 90)
			(size 0.59 0.64)
			(layers "B.Cu" "B.Mask" "B.Paste")
			(roundrect_rratio 0.25)
			(net 417 "GND")
			(pintype "passive")
		)
		(pad "2" smd roundrect
			(at 0.48 0 90)
			(size 0.59 0.64)
			(layers "B.Cu" "B.Mask" "B.Paste")
			(roundrect_rratio 0.25)
			(net 47 "+1V05")
			(pintype "passive")
		)
	)
	(footprint "antmicro-footprints:C_0402_1005Metric"
		(layer "B.Cu")
		(at 203.51 135.96 -90)
		(descr "Capacitor SMD 0402")
		(tags "capacitor SMD 0402")
		(property "Reference" "C52"
			(at -3.06 -0.49 90)
			(layer "B.SilkS")
			(effects
				(font
					(size 0.7 0.7)
					(thickness 0.15)
				)
				(justify left bottom mirror)
			)
		)
		(property "Value" "C_1n_0402"
			(at -1.022927 -2.155213 90)
			(layer "B.Fab")
			(hide yes)
			(effects
				(font
					(size 0.7 0.7)
					(thickness 0.15)
				)
				(justify left bottom mirror)
			)
		)
		(property "Datasheet" "https://www.murata.com/products/productdetail?partno=GRM1555C1H102JA01%23"
			(at 0 0 270)
			(layer "F.Fab")
			(hide yes)
			(effects
				(font
					(size 1.27 1.27)
					(thickness 0.15)
				)
			)
		)
		(property "Description" "SMD Multilayer Ceramic Capacitor, 1000 pF, 50 V, 0402 [1005 Metric], ± 5%, C0G / NP0, GRM Series"
			(at 0 0 270)
			(layer "F.Fab")
			(hide yes)
			(effects
				(font
					(size 1.27 1.27)
					(thickness 0.15)
				)
			)
		)
		(property "Author" "Antmicro"
			(at 67.55 339.47 0)
			(layer "B.Fab")
			(hide yes)
			(effects
				(font
					(size 1 1)
					(thickness 0.15)
				)
				(justify mirror)
			)
		)
		(property "Dielectric" "C0G"
			(at 67.55 339.47 0)
			(layer "B.Fab")
			(hide yes)
			(effects
				(font
					(size 1 1)
					(thickness 0.15)
				)
				(justify mirror)
			)
		)
		(property "License" "Apache-2.0"
			(at 67.55 339.47 0)
			(layer "B.Fab")
			(hide yes)
			(effects
				(font
					(size 1 1)
					(thickness 0.15)
				)
				(justify mirror)
			)
		)
		(property "MPN" "GRM1555C1H102JA01D"
			(at 67.55 339.47 0)
			(layer "B.Fab")
			(hide yes)
			(effects
				(font
					(size 1 1)
					(thickness 0.15)
				)
				(justify mirror)
			)
		)
		(property "Manufacturer" "Murata"
			(at 67.55 339.47 0)
			(layer "B.Fab")
			(hide yes)
			(effects
				(font
					(size 1 1)
					(thickness 0.15)
				)
				(justify mirror)
			)
		)
		(property "Public" ""
			(at 67.55 339.47 0)
			(layer "B.Fab")
			(hide yes)
			(effects
				(font
					(size 1 1)
					(thickness 0.15)
				)
				(justify mirror)
			)
		)
		(property "Val" "1n"
			(at 67.55 339.47 0)
			(layer "B.Fab")
			(hide yes)
			(effects
				(font
					(size 1 1)
					(thickness 0.15)
				)
				(justify mirror)
			)
		)
		(property "Voltage" "50V"
			(at 67.55 339.47 0)
			(layer "B.Fab")
			(hide yes)
			(effects
				(font
					(size 1 1)
					(thickness 0.15)
				)
				(justify mirror)
			)
		)
		(sheetname "/FPGA Supply/")
		(sheetfile "fpga-supply.kicad_sch")
		(attr smd)
		(fp_rect
			(start -0.925 0.47)
			(end 0.925 -0.47)
			(stroke
				(width 0.05)
				(type default)
			)
			(fill no)
			(layer "B.CrtYd")
		)
		(fp_line
			(start -0.494 0.25)
			(end 0.504 0.25)
			(stroke
				(width 0.15)
				(type solid)
			)
			(layer "B.Fab")
		)
		(fp_line
			(start 0.504 0.25)
			(end 0.504 -0.248)
			(stroke
				(width 0.15)
				(type solid)
			)
			(layer "B.Fab")
		)
		(fp_line
			(start -0.494 -0.248)
			(end -0.494 0.25)
			(stroke
				(width 0.15)
				(type solid)
			)
			(layer "B.Fab")
		)
		(fp_line
			(start 0.504 -0.248)
			(end -0.494 -0.248)
			(stroke
				(width 0.15)
				(type solid)
			)
			(layer "B.Fab")
		)
		(fp_text user "License: Apache-2.0"
			(at -0.939 -5.799 90)
			(layer "B.Fab")
			(effects
				(font
					(size 0.7 0.7)
					(thickness 0.15)
				)
				(justify left bottom mirror)
			)
		)
		(fp_text user "${REFERENCE}"
			(at -0.939 -4.599 90)
			(layer "B.Fab")
			(effects
				(font
					(size 0.7 0.7)
					(thickness 0.15)
				)
				(justify left bottom mirror)
			)
		)
		(fp_text user "Author: Antmicro"
			(at -0.939 -3.399 90)
			(layer "B.Fab")
			(effects
				(font
					(size 0.7 0.7)
					(thickness 0.15)
				)
				(justify left bottom mirror)
			)
		)
		(pad "1" smd roundrect
			(at -0.48 0 270)
			(size 0.59 0.64)
			(layers "B.Cu" "B.Mask" "B.Paste")
			(roundrect_rratio 0.25)
			(net 417 "GND")
			(pintype "passive")
		)
		(pad "2" smd roundrect
			(at 0.48 0 270)
			(size 0.59 0.64)
			(layers "B.Cu" "B.Mask" "B.Paste")
			(roundrect_rratio 0.25)
			(net 649 "VDD")
			(pintype "passive")
		)
	)
)
